FILE_TYPE = CONNECTIVITY;
{Allegro Design Entry HDL 16.6-p007 (v16-6-112F) 10/10/2012}
"PAGE_NUMBER" = 130;
0"NC";
1"GND\g";
2"GND\g";
3"GND\g";
4"GND\g";
5"GND\g";
6"P1V8_PCH_STBY\g";
7"GND\g";
8"GND\g";
9"GND\g";
10"P1V8_PCH_STBY\g";
11"GND\g";
12"GND\g";
13"P1V8_PCH_STBY\g";
14"P3V3_STBY\g";
15"P3V3_STBY\g";
16"P3V3_STBY\g";
17"P3V3_STBY\g";
18"GND\g";
19"P3V3_STBY\g";
20"P3V3_STBY\g";
21"P3V3_STBY\g";
22"A_PVCCRTC_EXT_CAP";
%"CAP_A"
"1","(1925,1600)","0","dev_discrete","I12";
;
ROOM"SB_DECOUPLING"
$SEC"1"
CDS_SEC"1"
CDS_LIB"dev_discrete"
BOM_COST"SB"
CDS_LOCATION"C2N20"
MATERIAL"X6S"
VOLTAGE"6.3V"
PACK_TYPE"0402V"
TOLERANCE"10%"
VALUE"1.0UF"
PART_NUMBER"D97712-004"
LOCATION"C2N20";
"B"
$PN"2"1;
"A"
$PN"1"21;
%"GND"
"1","(1925,1300)","0","mstr_symbols","I13";
;
HDL_POWER"GND"
ROOM"SB_DECOUPLING"
BODY_TYPE"PLUMBING"
CDS_LIB"mstr_symbols"
SIZE"1B"
BOM_COST"SB"
VOLTAGE"0";
"A\NAC"1;
%"GND"
"1","(650,2350)","0","mstr_symbols","I14";
;
HDL_POWER"GND"
ROOM"SB_DECOUPLING"
BODY_TYPE"PLUMBING"
SIZE"1B"
CDS_LIB"mstr_symbols"
BOM_COST"SB"
VOLTAGE"0";
"A\NAC"2;
%"CAP"
"1","(425,2650)","0","mstr_discrete","I15";
;
ROOM"SB_DECOUPLING"
CDS_LOCATION"C2N21"
$SEC"1"
CDS_SEC"1"
BOM_COST"SB"
CDS_LIB"mstr_discrete"
MATERIAL"X6S"
VOLTAGE"6.3V"
PACK_TYPE"0603"
TOLERANCE"20%"
VALUE"10UF"
PART_NUMBER"E15431-002"
LOCATION"C2N21";
"A"
$PN"1"20;
"B"
$PN"2"2;
%"CAP_A"
"1","(0,2025)","2","dev_discrete","I16";
;
$SEC"1"
CDS_SEC"1"
CDS_LIB"dev_discrete"
BOM_COST"SB"
CDS_LOCATION"C3N29"
ROOM"SB_DECOUPLING"
MATERIAL"X7R"
VOLTAGE"16V"
PACK_TYPE"0402V"
TOLERANCE"10%"
VALUE"0.1UF"
PART_NUMBER"A36096-030"
LOCATION"C3N29";
"B"
$PN"2"3;
"A"
$PN"1"22;
%"GND"
"1","(0,1725)","0","mstr_symbols","I17";
;
HDL_POWER"GND"
ROOM"SB_DECOUPLING"
BODY_TYPE"PLUMBING"
BOM_COST"SB"
SIZE"1B"
CDS_LIB"mstr_symbols"
VOLTAGE"0";
"A\NAC"3;
%"CAP"
"1","(-2550,4925)","0","mstr_discrete","I19";
;
ROOM"SB_DECOUPLING"
CDS_LOCATION"C8C3"
$SEC"1"
CDS_SEC"1"
BOM_COST"SB"
CDS_LIB"mstr_discrete"
MATERIAL"X6S"
VOLTAGE"6.3V"
PACK_TYPE"0603"
TOLERANCE"20%"
VALUE"10UF"
PART_NUMBER"E15431-002"
LOCATION"C8C3";
"A"
$PN"1"14;
"B"
$PN"2"8;
%"CAP"
"1","(1125,5003)","0","mstr_discrete","I2";
;
CDS_SEC"1"
ROOM"SB_DECOUPLING"
CDS_LOCATION"C7D2"
SEC"1"
CDS_LIB"mstr_discrete"
BOM_COST"SB"
SEC_TYPE"0603"
MATERIAL"X6S"
VOLTAGE"6.3V"
PACK_TYPE"0603"
TOLERANCE"20%"
VALUE"10UF"
PART_NUMBER"E15431-002"
LOCATION"C7D2";
"A"
$PN"1"17;
"B"
$PN"2"5;
%"CAP"
"1","(-2975,4925)","0","mstr_discrete","I20";
;
ROOM"SB_DECOUPLING"
CDS_LOCATION"C8C4"
$SEC"1"
CDS_SEC"1"
BOM_COST"SB"
CDS_LIB"mstr_discrete"
MATERIAL"X6S"
VOLTAGE"6.3V"
PACK_TYPE"0603"
TOLERANCE"20%"
VALUE"10UF"
PART_NUMBER"E15431-002"
LOCATION"C8C4";
"A"
$PN"1"14;
"B"
$PN"2"8;
%"CAP"
"1","(-3375,4925)","0","mstr_discrete","I21";
;
ROOM"SB_DECOUPLING"
CDS_LOCATION"C8C5"
$SEC"1"
CDS_SEC"1"
BOM_COST"SB"
CDS_LIB"mstr_discrete"
MATERIAL"X6S"
VOLTAGE"6.3V"
PACK_TYPE"0603"
TOLERANCE"20%"
VALUE"10UF"
PART_NUMBER"E15431-002"
LOCATION"C8C5";
"A"
$PN"1"14;
"B"
$PN"2"8;
%"CAP"
"1","(-3775,4925)","0","mstr_discrete","I22";
;
ROOM"SB_DECOUPLING"
CDS_LOCATION"C8C6"
$SEC"1"
CDS_SEC"1"
BOM_COST"SB"
CDS_LIB"mstr_discrete"
VOLTAGE"6.3V"
MATERIAL"X6S"
PACK_TYPE"0603"
TOLERANCE"20%"
VALUE"10UF"
PART_NUMBER"E15431-002"
LOCATION"C8C6";
"A"
$PN"1"14;
"B"
$PN"2"8;
%"CAP"
"1","(-4175,4925)","0","mstr_discrete","I24";
;
ROOM"SB_DECOUPLING"
CDS_LOCATION"C2N23"
$SEC"1"
CDS_SEC"1"
BOM_COST"SB"
CDS_LIB"mstr_discrete"
MATERIAL"X6S"
VOLTAGE"6.3V"
PACK_TYPE"0603"
TOLERANCE"20%"
VALUE"10UF"
PART_NUMBER"E15431-002"
LOCATION"C2N23";
"A"
$PN"1"14;
"B"
$PN"2"8;
%"CAP"
"1","(-4575,4925)","0","mstr_discrete","I25";
;
ROOM"SB_DECOUPLING"
CDS_LOCATION"C2N14"
$SEC"1"
CDS_SEC"1"
BOM_COST"SB"
CDS_LIB"mstr_discrete"
VOLTAGE"6.3V"
MATERIAL"X6S"
PACK_TYPE"0603"
TOLERANCE"20%"
VALUE"10UF"
PART_NUMBER"E15431-002"
LOCATION"C2N14";
"A"
$PN"1"14;
"B"
$PN"2"8;
%"GND"
"1","(-1475,3625)","0","mstr_symbols","I27";
;
HDL_POWER"GND"
ROOM"SB_DECOUPLING"
BODY_TYPE"PLUMBING"
BOM_COST"SB"
SIZE"1B"
CDS_LIB"mstr_symbols"
VOLTAGE"0.0V";
"A\NAC"4;
%"CAP"
"1","(-1475,3925)","0","mstr_discrete","I28";
;
ROOM"SB_DECOUPLING"
CDS_LOCATION"C2N17"
$SEC"1"
CDS_SEC"1"
BOM_COST"SB"
CDS_LIB"mstr_discrete"
MATERIAL"X6S"
VOLTAGE"6.3V"
PACK_TYPE"0603"
TOLERANCE"20%"
VALUE"10UF"
PART_NUMBER"E15431-002"
LOCATION"C2N17";
"A"
$PN"1"16;
"B"
$PN"2"4;
%"CAP_A"
"1","(-3450,3925)","0","dev_discrete","I29";
;
ROOM"SB_DECOUPLING"
$SEC"1"
CDS_SEC"1"
CDS_LIB"dev_discrete"
BOM_COST"SB"
CDS_LOCATION"C2N18"
MATERIAL"X6S"
VOLTAGE"6.3V"
PACK_TYPE"0402V"
TOLERANCE"10%"
VALUE"1.0UF"
PART_NUMBER"D97712-004"
LOCATION"C2N18";
"B"
$PN"2"9;
"A"
$PN"1"15;
%"GND"
"1","(1125,4725)","0","mstr_symbols","I3";
;
HDL_POWER"GND"
ROOM"SB_DECOUPLING"
BODY_TYPE"PLUMBING"
CDS_LIB"mstr_symbols"
SIZE"1B"
BOM_COST"SB"
VOLTAGE"0";
"A\NAC"5;
%"CAP_A"
"1","(-3100,2750)","0","dev_discrete","I30";
;
ROOM"SB_DECOUPLING"
$SEC"1"
CDS_SEC"1"
CDS_LIB"dev_discrete"
BOM_COST"SB"
CDS_LOCATION"C8B2"
MATERIAL"X6S"
VOLTAGE"4V"
PACK_TYPE"0603V"
TOLERANCE"20%"
VALUE"22.0UF"
PART_NUMBER"E15431-004"
LOCATION"C8B2";
"B"
$PN"2"11;
"A"
$PN"1"10;
%"P1V8_PCH_STBY"
"1","(-1975,2175)","0","mstr_symbols","I31";
;
HDL_POWER"P1V8_PCH_STBY"
ROOM"SB_DECOUPLING"
BODY_TYPE"PLUMBING"
CDS_LIB"mstr_symbols"
BOM_COST"SB"
VOLTAGE"1.8V";
"G\NAC"6;
%"CAP_A"
"1","(-1975,1900)","0","dev_discrete","I32";
;
ROOM"SB_DECOUPLING"
$SEC"1"
CDS_SEC"1"
CDS_LIB"dev_discrete"
BOM_COST"SB"
CDS_LOCATION"C8B3"
MATERIAL"X6S"
VOLTAGE"4V"
PACK_TYPE"0603V"
TOLERANCE"20%"
VALUE"22.0UF"
PART_NUMBER"E15431-004"
LOCATION"C8B3";
"B"
$PN"2"7;
"A"
$PN"1"6;
%"GND"
"1","(-1975,1575)","0","mstr_symbols","I33";
;
HDL_POWER"GND"
ROOM"SB_DECOUPLING"
BODY_TYPE"PLUMBING"
BOM_COST"SB"
SIZE"1B"
CDS_LIB"mstr_symbols"
VOLTAGE"0.0V";
"A\NAC"7;
%"CAP_A"
"1","(-3825,3925)","0","dev_discrete","I34";
;
ROOM"SB_DECOUPLING"
$SEC"1"
CDS_SEC"1"
CDS_LIB"dev_discrete"
BOM_COST"SB"
CDS_LOCATION"C2N25"
MATERIAL"X6S"
VOLTAGE"6.3V"
PACK_TYPE"0402V"
TOLERANCE"10%"
VALUE"1.0UF"
PART_NUMBER"D97712-004"
LOCATION"C2N25";
"B"
$PN"2"9;
"A"
$PN"1"15;
%"GND"
"1","(-4325,4575)","0","mstr_symbols","I35";
;
HDL_POWER"GND"
ROOM"SB_DECOUPLING"
BODY_TYPE"PLUMBING"
SIZE"1B"
CDS_LIB"mstr_symbols"
BOM_COST"SB"
VOLTAGE"0";
"A\NAC"8;
%"CAP_A"
"1","(-4200,3925)","0","dev_discrete","I37";
;
ROOM"SB_DECOUPLING"
$SEC"1"
CDS_SEC"1"
CDS_LIB"dev_discrete"
BOM_COST"SB"
CDS_LOCATION"C2M16"
MATERIAL"X6S"
VOLTAGE"6.3V"
PACK_TYPE"0402V"
TOLERANCE"10%"
VALUE"1.0UF"
PART_NUMBER"D97712-004"
LOCATION"C2M16";
"B"
$PN"2"9;
"A"
$PN"1"15;
%"CAP_A"
"1","(-3525,2750)","0","dev_discrete","I38";
;
ROOM"SB_DECOUPLING"
$SEC"1"
CDS_SEC"1"
CDS_LIB"dev_discrete"
BOM_COST"SB"
CDS_LOCATION"C7D3"
MATERIAL"X6S"
VOLTAGE"4V"
PACK_TYPE"0603V"
TOLERANCE"20%"
VALUE"22.0UF"
PART_NUMBER"E15431-004"
LOCATION"C7D3";
"B"
$PN"2"11;
"A"
$PN"1"10;
%"CAP_A"
"1","(-3925,2750)","0","dev_discrete","I39";
;
ROOM"SB_DECOUPLING"
$SEC"1"
CDS_SEC"1"
CDS_LIB"dev_discrete"
BOM_COST"SB"
CDS_LOCATION"C8B4"
MATERIAL"X6S"
VOLTAGE"4V"
PACK_TYPE"0603V"
TOLERANCE"20%"
VALUE"22.0UF"
PART_NUMBER"E15431-004"
LOCATION"C8B4";
"B"
$PN"2"11;
"A"
$PN"1"10;
%"CAP_A"
"1","(1725,2650)","0","dev_discrete","I4";
;
ROOM"SB_DECOUPLING"
$SEC"1"
CDS_SEC"1"
CDS_LIB"dev_discrete"
BOM_COST"SB"
CDS_LOCATION"C2N26"
MATERIAL"X6S"
VOLTAGE"6.3V"
PACK_TYPE"0402V"
TOLERANCE"10%"
VALUE"1.0UF"
PART_NUMBER"D97712-004"
LOCATION"C2N26";
"B"
$PN"2"2;
"A"
$PN"1"20;
%"GND"
"1","(-4375,3575)","0","mstr_symbols","I40";
;
HDL_POWER"GND"
ROOM"SB_DECOUPLING"
BODY_TYPE"PLUMBING"
CDS_LIB"mstr_symbols"
SIZE"1B"
BOM_COST"SB"
VOLTAGE"0";
"A\NAC"9;
%"CAP_A"
"1","(-4350,2750)","0","dev_discrete","I41";
;
ROOM"SB_DECOUPLING"
$SEC"1"
CDS_SEC"1"
CDS_LIB"dev_discrete"
BOM_COST"SB"
CDS_LOCATION"C8B1"
MATERIAL"X6S"
VOLTAGE"4V"
PACK_TYPE"0603V"
TOLERANCE"20%"
VALUE"22.0UF"
PART_NUMBER"E15431-004"
LOCATION"C8B1";
"B"
$PN"2"11;
"A"
$PN"1"10;
%"CAP_A"
"1","(-4600,3925)","0","dev_discrete","I42";
;
ROOM"SB_DECOUPLING"
$SEC"1"
CDS_SEC"1"
CDS_LIB"dev_discrete"
BOM_COST"SB"
CDS_LOCATION"C3N23"
MATERIAL"X6S"
VOLTAGE"6.3V"
PACK_TYPE"0402V"
TOLERANCE"10%"
VALUE"1.0UF"
PART_NUMBER"D97712-004"
LOCATION"C3N23";
"B"
$PN"2"9;
"A"
$PN"1"15;
%"CAP_A"
"1","(-4725,2750)","0","dev_discrete","I43";
;
ROOM"SB_DECOUPLING"
$SEC"1"
CDS_SEC"1"
CDS_LIB"dev_discrete"
BOM_COST"SB"
CDS_LOCATION"C2M1"
MATERIAL"X6S"
VOLTAGE"4V"
PACK_TYPE"0603V"
TOLERANCE"20%"
VALUE"22.0UF"
PART_NUMBER"E15431-004"
LOCATION"C2M1";
"B"
$PN"2"11;
"A"
$PN"1"10;
%"P1V8_PCH_STBY"
"1","(-4850,3025)","0","mstr_symbols","I44";
;
HDL_POWER"P1V8_PCH_STBY"
ROOM"SB_DECOUPLING"
BODY_TYPE"PLUMBING"
CDS_LIB"mstr_symbols"
BOM_COST"SB"
VOLTAGE"1.8V";
"G\NAC"10;
%"CAP_A"
"1","(-5150,2750)","0","dev_discrete","I45";
;
ROOM"SB_DECOUPLING"
$SEC"1"
CDS_SEC"1"
CDS_LIB"dev_discrete"
BOM_COST"SB"
CDS_LOCATION"C2M2"
MATERIAL"X6S"
VOLTAGE"4V"
PACK_TYPE"0603V"
TOLERANCE"20%"
VALUE"22.0UF"
PART_NUMBER"E15431-004"
LOCATION"C2M2";
"B"
$PN"2"11;
"A"
$PN"1"10;
%"GND"
"1","(-4075,2425)","0","mstr_symbols","I46";
;
HDL_POWER"GND"
ROOM"SB_DECOUPLING"
BODY_TYPE"PLUMBING"
BOM_COST"SB"
CDS_LIB"mstr_symbols"
SIZE"1B"
VOLTAGE"0";
"A\NAC"11;
%"CAP_A"
"1","(-3600,1475)","0","dev_discrete","I47";
;
ROOM"SB_DECOUPLING"
$SEC"1"
CDS_SEC"1"
CDS_LIB"dev_discrete"
BOM_COST"SB"
CDS_LOCATION"C2N15"
MATERIAL"X6S"
VOLTAGE"6.3V"
PACK_TYPE"0402V"
TOLERANCE"10%"
VALUE"1.0UF"
PART_NUMBER"D97712-004"
LOCATION"C2N15";
"B"
$PN"2"12;
"A"
$PN"1"13;
%"GND"
"1","(-3750,1150)","0","mstr_symbols","I48";
;
HDL_POWER"GND"
ROOM"SB_DECOUPLING"
BODY_TYPE"PLUMBING"
SIZE"1B"
CDS_LIB"mstr_symbols"
BOM_COST"SB"
VOLTAGE"0";
"A\NAC"12;
%"CAP_A"
"1","(-3975,1475)","0","dev_discrete","I49";
;
ROOM"SB_DECOUPLING"
$SEC"1"
CDS_SEC"1"
CDS_LIB"dev_discrete"
BOM_COST"SB"
CDS_LOCATION"C3N21"
MATERIAL"X6S"
VOLTAGE"6.3V"
PACK_TYPE"0402V"
TOLERANCE"10%"
VALUE"1.0UF"
PART_NUMBER"D97712-004"
LOCATION"C3N21";
"B"
$PN"2"12;
"A"
$PN"1"13;
%"CAP_A"
"1","(-4350,1475)","0","dev_discrete","I50";
;
ROOM"SB_DECOUPLING"
$SEC"1"
CDS_SEC"1"
CDS_LIB"dev_discrete"
BOM_COST"SB"
CDS_LOCATION"C3N25"
MATERIAL"X6S"
VOLTAGE"6.3V"
PACK_TYPE"0402V"
TOLERANCE"10%"
VALUE"1.0UF"
PART_NUMBER"D97712-004"
LOCATION"C3N25";
"B"
$PN"2"12;
"A"
$PN"1"13;
%"P1V8_PCH_STBY"
"1","(-4950,1750)","0","mstr_symbols","I51";
;
HDL_POWER"P1V8_PCH_STBY"
ROOM"SB_DECOUPLING"
BODY_TYPE"PLUMBING"
CDS_LIB"mstr_symbols"
BOM_COST"SB"
VOLTAGE"1.8V";
"G\NAC"13;
%"CAP_A"
"1","(-4775,1475)","0","dev_discrete","I52";
;
ROOM"SB_DECOUPLING"
$SEC"1"
CDS_SEC"1"
CDS_LIB"dev_discrete"
BOM_COST"SB"
CDS_LOCATION"C2N16"
MATERIAL"X6S"
VOLTAGE"6.3V"
PACK_TYPE"0402V"
TOLERANCE"10%"
VALUE"1.0UF"
PART_NUMBER"D97712-004"
LOCATION"C2N16";
"B"
$PN"2"12;
"A"
$PN"1"13;
%"CAP_A"
"1","(-5200,1475)","0","dev_discrete","I53";
;
ROOM"SB_DECOUPLING"
$SEC"1"
CDS_SEC"1"
CDS_LIB"dev_discrete"
BOM_COST"SB"
CDS_LOCATION"C3N22"
MATERIAL"X6S"
VOLTAGE"6.3V"
PACK_TYPE"0402V"
TOLERANCE"10%"
VALUE"1.0UF"
PART_NUMBER"D97712-004"
LOCATION"C3N22";
"B"
$PN"2"12;
"A"
$PN"1"13;
%"P3V3_STBY"
"1","(-4325,5175)","0","mstr_symbols","I54";
;
HDL_POWER"P3V3_STBY"
BODY_TYPE"PLUMBING"
SIZE"1B"
CDS_LIB"mstr_symbols"
VOLTAGE"3.3V";
"G\NAC"14;
%"P3V3_STBY"
"1","(-4375,4250)","0","mstr_symbols","I55";
;
HDL_POWER"P3V3_STBY"
BODY_TYPE"PLUMBING"
CDS_LIB"mstr_symbols"
SIZE"1B"
VOLTAGE"3.3V";
"G\NAC"15;
%"P3V3_STBY"
"1","(-1475,4225)","0","mstr_symbols","I58";
;
HDL_POWER"P3V3_STBY"
BODY_TYPE"PLUMBING"
CDS_LIB"mstr_symbols"
SIZE"1B"
VOLTAGE"3.3V";
"G\NAC"16;
%"P3V3_STBY"
"1","(1125,5200)","0","mstr_symbols","I59";
;
HDL_POWER"P3V3_STBY"
BODY_TYPE"PLUMBING"
SIZE"1B"
CDS_LIB"mstr_symbols"
VOLTAGE"3.3V";
"G\NAC"17;
%"GND"
"1","(1175,3600)","0","mstr_symbols","I6";
;
HDL_POWER"GND"
ROOM"SB_DECOUPLING"
BODY_TYPE"PLUMBING"
CDS_LIB"mstr_symbols"
SIZE"1B"
BOM_COST"SB"
VOLTAGE"0";
"A\NAC"18;
%"P3V3_STBY"
"1","(1175,4175)","0","mstr_symbols","I60";
;
HDL_POWER"P3V3_STBY"
BODY_TYPE"PLUMBING"
SIZE"1B"
CDS_LIB"mstr_symbols"
VOLTAGE"3.3V";
"G\NAC"19;
%"P3V3_STBY"
"1","(650,2925)","0","mstr_symbols","I61";
;
HDL_POWER"P3V3_STBY"
BODY_TYPE"PLUMBING"
SIZE"1B"
CDS_LIB"mstr_symbols"
VOLTAGE"3.3V";
"G\NAC"20;
%"P3V3_STBY"
"1","(1925,1875)","0","mstr_symbols","I62";
;
HDL_POWER"P3V3_STBY"
BODY_TYPE"PLUMBING"
SIZE"1B"
CDS_LIB"mstr_symbols"
VOLTAGE"3.3V";
"G\NAC"21;
%"CAP_A"
"1","(1175,3900)","0","dev_discrete","I7";
;
ROOM"SB_DECOUPLING"
$SEC"1"
CDS_SEC"1"
CDS_LIB"dev_discrete"
BOM_COST"SB"
CDS_LOCATION"C2N19"
MATERIAL"X6S"
VOLTAGE"6.3V"
PACK_TYPE"0402V"
TOLERANCE"10%"
VALUE"1.0UF"
PART_NUMBER"D97712-004"
LOCATION"C2N19";
"B"
$PN"2"18;
"A"
$PN"1"19;
%"CAP"
"1","(1300,2650)","0","mstr_discrete","I8";
;
ROOM"SB_DECOUPLING"
CDS_LOCATION"C2N24"
$SEC"1"
CDS_SEC"1"
BOM_COST"SB"
CDS_LIB"mstr_discrete"
MATERIAL"X6S"
VOLTAGE"6.3V"
PACK_TYPE"0603"
TOLERANCE"20%"
VALUE"10UF"
PART_NUMBER"E15431-002"
LOCATION"C2N24";
"A"
$PN"1"20;
"B"
$PN"2"2;
%"CAP"
"1","(875,2650)","0","mstr_discrete","I9";
;
ROOM"SB_DECOUPLING"
CDS_LOCATION"C2N22"
$SEC"1"
CDS_SEC"1"
BOM_COST"SB"
CDS_LIB"mstr_discrete"
MATERIAL"X6S"
VOLTAGE"6.3V"
PACK_TYPE"0603"
TOLERANCE"20%"
VALUE"10UF"
PART_NUMBER"E15431-002"
LOCATION"C2N22";
"A"
$PN"1"20;
"B"
$PN"2"2;
END.
